FILE_TYPE = MACRO_DRAWING;
SET COLOR_WIRE YELLOW;
SET COLOR_PROP ORANGE;
SET COLOR_DOT WHITE;
SET COLOR_ARC YELLOW;
SET COLOR_BODY GREEN;
SET COLOR_NOTE PURPLE;
SET PROP_DISPLAY VALUE;
SET PAGE_NUMBER P304;
FORCEADD OFFPAGE..1
(-3825 -500);
PAINT AQUA (-3825 -500);
FORCEPROP 2 LAST $XR1 129 
J 0
(-4227 -500);
DISPLAY 0.638298 (-4227 -500);
PAINT MONO (-4227 -500);
FORCEPROP 2 LAST $XR0 216 
J 0
(-4107 -500);
DISPLAY 0.638298 (-4107 -500);
PAINT MONO (-4107 -500);
FORCEPROP 2 LAST PATH I1
J 0
(-4100 -450);
DISPLAY 1.021277 (-4100 -450);
DISPLAY INVISIBLE (-4100 -450);
FORCEPROP 1 LAST COMMENT_BODY TRUE
J 0
(-3700 -600);
DISPLAY 0.872340 (-3700 -600);
PAINT GREEN (-3700 -600);
DISPLAY INVISIBLE (-3700 -600);
FORCEPROP 1 LAST OFFPAGE TRUE
J 0
(-3500 -625);
DISPLAY 0.872340 (-3500 -625);
PAINT AQUA (-3500 -625);
DISPLAY INVISIBLE (-3500 -625);
FORCEPROP 2 LAST CDS_LIB standard
J 0
(-3825 -500);
DISPLAY INVISIBLE (-3825 -500);
FORCEADD UNIVERSAL_GND..1
(-2800 2225);
FORCEPROP 3 LASTPIN (-2800 2275) SIG_NAME GND\g
J 0
(-2790 2285);
DISPLAY 0.659574 (-2790 2285);
PAINT MONO (-2790 2285);
DISPLAY INVISIBLE (-2790 2285);
FORCEPROP 1 LAST PATH I10
J 0
(-2725 2225);
DISPLAY 0.872340 (-2725 2225);
PAINT AQUA (-2725 2225);
DISPLAY INVISIBLE (-2725 2225);
FORCEPROP 2 LAST CDS_LIB logical_power
J 0
(-2800 2225);
DISPLAY INVISIBLE (-2800 2225);
FORCEPROP 1 LAST HDL_POWER GND
J 1
(-2775 2150);
DISPLAY 0.872340 (-2775 2150);
PAINT GREEN (-2775 2150);
DISPLAY INVISIBLE (-2775 2150);
FORCEADD Q_LED..1
R 2
(-1800 1175);
FORCEPROP 1 LAST PART_NUMBER BEBL0172Z00
J 0
(-1900 950);
DISPLAY 0.574468 (-1900 950);
PAINT GREEN (-1900 950);
DISPLAY INVISIBLE (-1900 950);
FORCEPROP 2 LAST COLOR LED_BLUE
J 0
(-1900 1050);
DISPLAY 0.638298 (-1900 1050);
FORCEPROP 2 LAST MANUF_PN LTST-C281TBKT-5A
J 0
(-1900 900);
DISPLAY 0.638298 (-1900 900);
FORCEPROP 1 LAST MATERIAL IC
J 0
(-1775 1000);
DISPLAY 0.723404 (-1775 1000);
PAINT GREEN (-1775 1000);
FORCEPROP 0 LAST PACK_TYPE SMLF
J 0
(-1900 1000);
DISPLAY 0.638298 (-1900 1000);
FORCEPROP 1 LAST LOCATION D67
J 0
(-1900 1100);
DISPLAY 0.723404 (-1900 1100);
PAINT GREEN (-1900 1100);
FORCEPROP 0 LASTPIN (-1650 1175) $PN A
J 0
(-1640 1185);
DISPLAY 0.808511 (-1640 1185);
FORCEPROP 0 LASTPIN (-1950 1175) $PN C
J 2
(-1960 1185);
DISPLAY 0.808511 (-1960 1185);
FORCEPROP 1 LAST PATH I12
J 2
(-1925 1255);
DISPLAY 0.723404 (-1925 1255);
PAINT GREEN (-1925 1255);
DISPLAY INVISIBLE (-1925 1255);
FORCEPROP 2 LAST CDS_LIB pure_quanta
J 0
(-1800 1175);
DISPLAY INVISIBLE (-1800 1175);
FORCEPROP 1 LAST NEEDS_NO_SIZE TRUE
J 2
(-1778 1197);
DISPLAY 0.468085 (-1778 1197);
PAINT GREEN (-1778 1197);
DISPLAY INVISIBLE (-1778 1197);
FORCEPROP 0 LAST $SEC 1
J 0
(-1900 1150);
DISPLAY INVISIBLE (-1900 1150);
FORCEPROP 0 LAST CDS_SEC 1
J 0
(-1900 1150);
DISPLAY INVISIBLE (-1900 1150);
FORCEADD UNIVERSAL_POWER..1
(275 0);
FORCEPROP 3 LASTPIN (275 -50) SIG_NAME P3V3_AUX\g
J 0
(285 -40);
DISPLAY 0.659574 (285 -40);
PAINT MONO (285 -40);
DISPLAY INVISIBLE (285 -40);
FORCEPROP 1 LAST HDL_POWER P3V3_AUX
J 1
(275 50);
DISPLAY 0.723404 (275 50);
PAINT GREEN (275 50);
FORCEPROP 1 LAST PATH I14
J 0
(325 25);
DISPLAY 0.872340 (325 25);
PAINT AQUA (325 25);
DISPLAY INVISIBLE (325 25);
FORCEPROP 2 LAST CDS_LIB logical_power
J 0
(275 0);
DISPLAY INVISIBLE (275 0);
FORCEADD UNIVERSAL_POWER..1
(150 1350);
FORCEPROP 3 LASTPIN (150 1300) SIG_NAME P3V3_AUX\g
J 0
(160 1310);
DISPLAY 0.659574 (160 1310);
PAINT MONO (160 1310);
DISPLAY INVISIBLE (160 1310);
FORCEPROP 1 LAST HDL_POWER P3V3_AUX
J 1
(150 1400);
DISPLAY 0.723404 (150 1400);
PAINT GREEN (150 1400);
FORCEPROP 1 LAST PATH I16
J 0
(200 1375);
DISPLAY 0.872340 (200 1375);
PAINT AQUA (200 1375);
DISPLAY INVISIBLE (200 1375);
FORCEPROP 2 LAST CDS_LIB logical_power
J 0
(150 1350);
DISPLAY INVISIBLE (150 1350);
FORCEADD OFFPAGE..1
(625 2675);
PAINT AQUA (625 2675);
FORCEPROP 2 LAST $XR1 130 
J 0
(253 2675);
DISPLAY 0.638298 (253 2675);
PAINT MONO (253 2675);
FORCEPROP 2 LAST $XR0 216 
J 0
(373 2675);
DISPLAY 0.638298 (373 2675);
PAINT MONO (373 2675);
FORCEPROP 1 LAST COMMENT_BODY TRUE
J 0
(750 2575);
DISPLAY 0.872340 (750 2575);
PAINT GREEN (750 2575);
DISPLAY INVISIBLE (750 2575);
FORCEPROP 1 LAST OFFPAGE TRUE
J 0
(950 2550);
DISPLAY 0.872340 (950 2550);
PAINT AQUA (950 2550);
DISPLAY INVISIBLE (950 2550);
FORCEPROP 2 LAST CDS_LIB standard
J 0
(625 2675);
DISPLAY INVISIBLE (625 2675);
FORCEPROP 2 LAST PATH I17
J 0
(375 2725);
DISPLAY 1.021277 (375 2725);
DISPLAY INVISIBLE (375 2725);
FORCEADD UNIVERSAL_GND..1
(-2800 3825);
FORCEPROP 3 LASTPIN (-2800 3875) SIG_NAME GND\g
J 0
(-2790 3885);
DISPLAY 0.659574 (-2790 3885);
PAINT MONO (-2790 3885);
DISPLAY INVISIBLE (-2790 3885);
FORCEPROP 1 LAST PATH I19
J 0
(-2725 3825);
DISPLAY 0.872340 (-2725 3825);
PAINT AQUA (-2725 3825);
DISPLAY INVISIBLE (-2725 3825);
FORCEPROP 2 LAST CDS_LIB logical_power
J 0
(-2800 3825);
DISPLAY INVISIBLE (-2800 3825);
FORCEPROP 1 LAST HDL_POWER GND
J 1
(-2775 3750);
DISPLAY 0.872340 (-2775 3750);
PAINT GREEN (-2775 3750);
DISPLAY INVISIBLE (-2775 3750);
FORCEADD OFFPAGE..1
(-3975 850);
PAINT AQUA (-3975 850);
FORCEPROP 2 LAST $XR1 129 
J 0
(-4227 814);
DISPLAY 0.638298 (-4227 814);
PAINT MONO (-4227 814);
FORCEPROP 2 LAST $XR0 216 
J 0
(-4227 850);
DISPLAY 0.638298 (-4227 850);
PAINT MONO (-4227 850);
FORCEPROP 2 LAST PATH I2
J 0
(-4225 975);
DISPLAY 1.021277 (-4225 975);
DISPLAY INVISIBLE (-4225 975);
FORCEPROP 1 LAST COMMENT_BODY TRUE
J 0
(-3850 750);
DISPLAY 0.872340 (-3850 750);
PAINT GREEN (-3850 750);
DISPLAY INVISIBLE (-3850 750);
FORCEPROP 1 LAST OFFPAGE TRUE
J 0
(-3650 725);
DISPLAY 0.872340 (-3650 725);
PAINT AQUA (-3650 725);
DISPLAY INVISIBLE (-3650 725);
FORCEPROP 2 LAST CDS_LIB standard
J 0
(-3975 850);
DISPLAY INVISIBLE (-3975 850);
FORCEADD Q_LED..1
R 2
(-1775 2850);
FORCEPROP 1 LAST PART_NUMBER BEBL0172Z00
J 0
(-1875 2625);
DISPLAY 0.574468 (-1875 2625);
PAINT GREEN (-1875 2625);
DISPLAY INVISIBLE (-1875 2625);
FORCEPROP 1 LAST MATERIAL IC
J 0
(-1750 2675);
DISPLAY 0.723404 (-1750 2675);
PAINT GREEN (-1750 2675);
FORCEPROP 0 LAST PACK_TYPE SMLF
J 0
(-1875 2675);
DISPLAY 0.638298 (-1875 2675);
FORCEPROP 2 LAST COLOR LED_BLUE
J 0
(-1875 2725);
DISPLAY 0.638298 (-1875 2725);
FORCEPROP 2 LAST MANUF_PN LTST-C281TBKT-5A
J 0
(-1875 2575);
DISPLAY 0.638298 (-1875 2575);
FORCEPROP 1 LAST LOCATION D66
J 0
(-1875 2775);
DISPLAY 0.723404 (-1875 2775);
PAINT GREEN (-1875 2775);
FORCEPROP 0 LASTPIN (-1625 2850) $PN A
J 0
(-1615 2860);
DISPLAY 0.808511 (-1615 2860);
FORCEPROP 0 LASTPIN (-1925 2850) $PN C
J 2
(-1935 2860);
DISPLAY 0.808511 (-1935 2860);
FORCEPROP 1 LAST PATH I20
J 2
(-1900 2930);
DISPLAY 0.723404 (-1900 2930);
PAINT GREEN (-1900 2930);
DISPLAY INVISIBLE (-1900 2930);
FORCEPROP 1 LAST NEEDS_NO_SIZE TRUE
J 2
(-1753 2872);
DISPLAY 0.468085 (-1753 2872);
PAINT GREEN (-1753 2872);
DISPLAY INVISIBLE (-1753 2872);
FORCEPROP 2 LAST CDS_LIB pure_quanta
J 0
(-1775 2850);
DISPLAY INVISIBLE (-1775 2850);
FORCEPROP 0 LAST $SEC 1
J 0
(-1875 2825);
DISPLAY INVISIBLE (-1875 2825);
FORCEPROP 0 LAST CDS_SEC 1
J 0
(-1875 2825);
DISPLAY INVISIBLE (-1875 2825);
FORCEADD Q_LED..1
R 2
(-1775 4450);
FORCEPROP 1 LAST PART_NUMBER BEBL0172Z00
J 0
(-1875 4225);
DISPLAY 0.574468 (-1875 4225);
PAINT GREEN (-1875 4225);
DISPLAY INVISIBLE (-1875 4225);
FORCEPROP 1 LAST MATERIAL IC
J 0
(-1750 4275);
DISPLAY 0.723404 (-1750 4275);
PAINT GREEN (-1750 4275);
FORCEPROP 0 LAST PACK_TYPE SMLF
J 0
(-1875 4275);
DISPLAY 0.638298 (-1875 4275);
FORCEPROP 2 LAST COLOR LED_BLUE
J 0
(-1875 4325);
DISPLAY 0.638298 (-1875 4325);
FORCEPROP 2 LAST MANUF_PN LTST-C281TBKT-5A
J 0
(-1875 4175);
DISPLAY 0.638298 (-1875 4175);
FORCEPROP 1 LAST LOCATION D65
J 0
(-1875 4375);
DISPLAY 0.723404 (-1875 4375);
PAINT GREEN (-1875 4375);
FORCEPROP 0 LASTPIN (-1625 4450) $PN A
J 0
(-1615 4460);
DISPLAY 0.808511 (-1615 4460);
FORCEPROP 0 LASTPIN (-1925 4450) $PN C
J 2
(-1935 4460);
DISPLAY 0.808511 (-1935 4460);
FORCEPROP 1 LAST PATH I21
J 2
(-1900 4530);
DISPLAY 0.723404 (-1900 4530);
PAINT GREEN (-1900 4530);
DISPLAY INVISIBLE (-1900 4530);
FORCEPROP 1 LAST NEEDS_NO_SIZE TRUE
J 2
(-1753 4472);
DISPLAY 0.468085 (-1753 4472);
PAINT GREEN (-1753 4472);
DISPLAY INVISIBLE (-1753 4472);
FORCEPROP 2 LAST CDS_LIB pure_quanta
J 0
(-1775 4450);
DISPLAY INVISIBLE (-1775 4450);
FORCEPROP 0 LAST $SEC 1
J 0
(-1875 4425);
DISPLAY INVISIBLE (-1875 4425);
FORCEPROP 0 LAST CDS_SEC 1
J 0
(-1875 4425);
DISPLAY INVISIBLE (-1875 4425);
FORCEADD UNIVERSAL_POWER..1
(175 3025);
FORCEPROP 3 LASTPIN (175 2975) SIG_NAME P3V3_AUX\g
J 0
(185 2985);
DISPLAY 0.659574 (185 2985);
PAINT MONO (185 2985);
DISPLAY INVISIBLE (185 2985);
FORCEPROP 1 LAST HDL_POWER P3V3_AUX
J 1
(175 3075);
DISPLAY 0.723404 (175 3075);
PAINT GREEN (175 3075);
FORCEPROP 1 LAST PATH I24
J 0
(225 3050);
DISPLAY 0.872340 (225 3050);
PAINT AQUA (225 3050);
DISPLAY INVISIBLE (225 3050);
FORCEPROP 2 LAST CDS_LIB logical_power
J 0
(175 3025);
DISPLAY INVISIBLE (175 3025);
FORCEADD OFFPAGE..1
(525 4100);
PAINT AQUA (525 4100);
FORCEPROP 2 LAST $XR1 130 
J 0
(153 4100);
DISPLAY 0.638298 (153 4100);
PAINT MONO (153 4100);
FORCEPROP 2 LAST $XR0 216 
J 0
(273 4100);
DISPLAY 0.638298 (273 4100);
PAINT MONO (273 4100);
FORCEPROP 2 LAST PATH I25
J 0
(275 4150);
DISPLAY 1.021277 (275 4150);
DISPLAY INVISIBLE (275 4150);
FORCEPROP 2 LAST CDS_LIB standard
J 0
(525 4100);
DISPLAY INVISIBLE (525 4100);
FORCEPROP 1 LAST OFFPAGE TRUE
J 0
(850 3975);
DISPLAY 0.872340 (850 3975);
PAINT AQUA (850 3975);
DISPLAY INVISIBLE (850 3975);
FORCEPROP 1 LAST COMMENT_BODY TRUE
J 0
(650 4000);
DISPLAY 0.872340 (650 4000);
PAINT GREEN (650 4000);
DISPLAY INVISIBLE (650 4000);
FORCEADD UNIVERSAL_POWER..1
(175 4600);
FORCEPROP 3 LASTPIN (175 4550) SIG_NAME P3V3_AUX\g
J 0
(185 4560);
DISPLAY 0.659574 (185 4560);
PAINT MONO (185 4560);
DISPLAY INVISIBLE (185 4560);
FORCEPROP 1 LAST HDL_POWER P3V3_AUX
J 1
(175 4650);
DISPLAY 0.723404 (175 4650);
PAINT GREEN (175 4650);
FORCEPROP 1 LAST PATH I26
J 0
(225 4625);
DISPLAY 0.872340 (225 4625);
PAINT AQUA (225 4625);
DISPLAY INVISIBLE (225 4625);
FORCEPROP 2 LAST CDS_LIB logical_power
J 0
(175 4600);
DISPLAY INVISIBLE (175 4600);
FORCEADD UNIVERSAL_GND..1
(1675 3800);
FORCEPROP 3 LASTPIN (1675 3850) SIG_NAME GND\g
J 0
(1685 3860);
DISPLAY 0.659574 (1685 3860);
PAINT MONO (1685 3860);
DISPLAY INVISIBLE (1685 3860);
FORCEPROP 2 LAST CDS_LIB logical_power
J 0
(1675 3800);
DISPLAY INVISIBLE (1675 3800);
FORCEPROP 1 LAST PATH I29
J 0
(1750 3800);
DISPLAY 0.872340 (1750 3800);
PAINT AQUA (1750 3800);
DISPLAY INVISIBLE (1750 3800);
FORCEPROP 1 LAST HDL_POWER GND
J 1
(1700 3725);
DISPLAY 0.872340 (1700 3725);
PAINT GREEN (1700 3725);
DISPLAY INVISIBLE (1700 3725);
FORCEADD OFFPAGE..1
(-3950 2525);
PAINT AQUA (-3950 2525);
FORCEPROP 2 LAST $XR1 129 
J 0
(-4202 2489);
DISPLAY 0.638298 (-4202 2489);
PAINT MONO (-4202 2489);
FORCEPROP 2 LAST $XR0 216 
J 0
(-4202 2525);
DISPLAY 0.638298 (-4202 2525);
PAINT MONO (-4202 2525);
FORCEPROP 2 LAST PATH I3
J 0
(-4200 2600);
DISPLAY 1.021277 (-4200 2600);
DISPLAY INVISIBLE (-4200 2600);
FORCEPROP 2 LAST CDS_LIB standard
J 0
(-3950 2525);
DISPLAY INVISIBLE (-3950 2525);
FORCEPROP 1 LAST OFFPAGE TRUE
J 0
(-3625 2400);
DISPLAY 0.872340 (-3625 2400);
PAINT AQUA (-3625 2400);
DISPLAY INVISIBLE (-3625 2400);
FORCEPROP 1 LAST COMMENT_BODY TRUE
J 0
(-3825 2425);
DISPLAY 0.872340 (-3825 2425);
PAINT GREEN (-3825 2425);
DISPLAY INVISIBLE (-3825 2425);
FORCEADD Q_LED..1
R 2
(2700 3000);
FORCEPROP 1 LAST PART_NUMBER BEBL0172Z00
J 0
(2600 2775);
DISPLAY 0.574468 (2600 2775);
PAINT GREEN (2600 2775);
DISPLAY INVISIBLE (2600 2775);
FORCEPROP 1 LAST MATERIAL IC
J 0
(2725 2825);
DISPLAY 0.723404 (2725 2825);
PAINT GREEN (2725 2825);
FORCEPROP 2 LAST COLOR LED_BLUE
J 0
(2600 2875);
DISPLAY 0.638298 (2600 2875);
FORCEPROP 2 LAST MANUF_PN LTST-C281TBKT-5A
J 0
(2600 2725);
DISPLAY 0.638298 (2600 2725);
FORCEPROP 0 LAST PACK_TYPE SMLF
J 0
(2600 2825);
DISPLAY 0.638298 (2600 2825);
FORCEPROP 1 LAST LOCATION D70
J 0
(2600 2925);
DISPLAY 0.723404 (2600 2925);
PAINT GREEN (2600 2925);
FORCEPROP 0 LASTPIN (2850 3000) $PN A
J 0
(2860 3010);
DISPLAY 0.808511 (2860 3010);
FORCEPROP 0 LASTPIN (2550 3000) $PN C
J 2
(2540 3010);
DISPLAY 0.808511 (2540 3010);
FORCEPROP 1 LAST PATH I31
J 2
(2575 3080);
DISPLAY 0.723404 (2575 3080);
PAINT GREEN (2575 3080);
DISPLAY INVISIBLE (2575 3080);
FORCEPROP 2 LAST CDS_LIB pure_quanta
J 0
(2700 3000);
DISPLAY INVISIBLE (2700 3000);
FORCEPROP 1 LAST NEEDS_NO_SIZE TRUE
J 2
(2722 3022);
DISPLAY 0.468085 (2722 3022);
PAINT GREEN (2722 3022);
DISPLAY INVISIBLE (2722 3022);
FORCEPROP 0 LAST $SEC 1
J 0
(2600 2975);
DISPLAY INVISIBLE (2600 2975);
FORCEPROP 0 LAST CDS_SEC 1
J 0
(2600 2975);
DISPLAY INVISIBLE (2600 2975);
FORCEADD Q_LED..1
R 2
(2700 4425);
FORCEPROP 1 LAST PART_NUMBER BEBL0172Z00
J 0
(2600 4200);
DISPLAY 0.574468 (2600 4200);
PAINT GREEN (2600 4200);
DISPLAY INVISIBLE (2600 4200);
FORCEPROP 0 LAST PACK_TYPE SMLF
J 0
(2600 4250);
DISPLAY 0.638298 (2600 4250);
FORCEPROP 2 LAST COLOR LED_BLUE
J 0
(2600 4300);
DISPLAY 0.638298 (2600 4300);
FORCEPROP 1 LAST MATERIAL IC
J 0
(2725 4250);
DISPLAY 0.723404 (2725 4250);
PAINT GREEN (2725 4250);
FORCEPROP 2 LAST MANUF_PN LTST-C281TBKT-5A
J 0
(2600 4150);
DISPLAY 0.638298 (2600 4150);
FORCEPROP 1 LAST LOCATION D69
J 0
(2600 4350);
DISPLAY 0.723404 (2600 4350);
PAINT GREEN (2600 4350);
FORCEPROP 0 LASTPIN (2850 4425) $PN A
J 0
(2860 4435);
DISPLAY 0.808511 (2860 4435);
FORCEPROP 0 LASTPIN (2550 4425) $PN C
J 2
(2540 4435);
DISPLAY 0.808511 (2540 4435);
FORCEPROP 1 LAST PATH I32
J 2
(2575 4505);
DISPLAY 0.723404 (2575 4505);
PAINT GREEN (2575 4505);
DISPLAY INVISIBLE (2575 4505);
FORCEPROP 1 LAST NEEDS_NO_SIZE TRUE
J 2
(2722 4447);
DISPLAY 0.468085 (2722 4447);
PAINT GREEN (2722 4447);
DISPLAY INVISIBLE (2722 4447);
FORCEPROP 2 LAST CDS_LIB pure_quanta
J 0
(2700 4425);
DISPLAY INVISIBLE (2700 4425);
FORCEPROP 0 LAST $SEC 1
J 0
(2600 4400);
DISPLAY INVISIBLE (2600 4400);
FORCEPROP 0 LAST CDS_SEC 1
J 0
(2600 4400);
DISPLAY INVISIBLE (2600 4400);
FORCEADD UNIVERSAL_POWER..1
(4750 3175);
FORCEPROP 3 LASTPIN (4750 3125) SIG_NAME P3V3_AUX\g
J 0
(4760 3135);
DISPLAY 0.659574 (4760 3135);
PAINT MONO (4760 3135);
DISPLAY INVISIBLE (4760 3135);
FORCEPROP 1 LAST HDL_POWER P3V3_AUX
J 1
(4750 3225);
DISPLAY 0.723404 (4750 3225);
PAINT GREEN (4750 3225);
FORCEPROP 1 LAST PATH I35
J 0
(4800 3200);
DISPLAY 0.872340 (4800 3200);
PAINT AQUA (4800 3200);
DISPLAY INVISIBLE (4800 3200);
FORCEPROP 2 LAST CDS_LIB logical_power
J 0
(4750 3175);
DISPLAY INVISIBLE (4750 3175);
FORCEADD UNIVERSAL_POWER..1
(4675 4600);
FORCEPROP 3 LASTPIN (4675 4550) SIG_NAME P3V3_AUX\g
J 0
(4685 4560);
DISPLAY 0.659574 (4685 4560);
PAINT MONO (4685 4560);
DISPLAY INVISIBLE (4685 4560);
FORCEPROP 1 LAST HDL_POWER P3V3_AUX
J 1
(4675 4650);
DISPLAY 0.723404 (4675 4650);
PAINT GREEN (4675 4650);
FORCEPROP 1 LAST PATH I36
J 0
(4725 4625);
DISPLAY 0.872340 (4725 4625);
PAINT AQUA (4725 4625);
DISPLAY INVISIBLE (4725 4625);
FORCEPROP 2 LAST CDS_LIB logical_power
J 0
(4675 4600);
DISPLAY INVISIBLE (4675 4600);
FORCEADD Q_RES..1
(-400 4450);
FORCEPROP 1 LAST PART_NUMBER CS11302FB03
J 0
(-625 4550);
DISPLAY 0.638298 (-625 4550);
DISPLAY INVISIBLE (-625 4550);
FORCEPROP 1 LAST VALUE 130
J 2
(-200 4450);
DISPLAY 0.638298 (-200 4450);
FORCEPROP 1 LAST TOLERANCE 1%
J 0
(-175 4450);
DISPLAY 0.638298 (-175 4450);
FORCEPROP 1 LAST WATTAGE 1/16W
J 2
(-250 4400);
DISPLAY 0.638298 (-250 4400);
FORCEPROP 1 LAST PACK_TYPE 0402LF
J 0
(-100 4450);
DISPLAY 0.638298 (-100 4450);
FORCEPROP 1 LAST MATERIAL CHIP
J 0
(-550 4400);
DISPLAY 0.638298 (-550 4400);
FORCEPROP 1 LAST LOCATION R1371
J 0
(-650 4450);
DISPLAY 0.787234 (-650 4450);
FORCEPROP 1 LASTPIN (-500 4450) $PN 1
J 0
(-488 4462);
DISPLAY 0.787234 (-488 4462);
PAINT MONO (-488 4462);
FORCEPROP 1 LASTPIN (-300 4450) $PN 2
J 0
(-338 4462);
DISPLAY 0.787234 (-338 4462);
PAINT MONO (-338 4462);
FORCEPROP 1 LAST PATH I49
J 0
(-450 4600);
DISPLAY 0.978723 (-450 4600);
PAINT WHITE (-450 4600);
DISPLAY INVISIBLE (-450 4600);
FORCEPROP 2 LAST CDS_LIB pure_quanta
J 0
(-400 4450);
DISPLAY INVISIBLE (-400 4450);
FORCEPROP 0 LAST $SEC 1
J 0
(-250 4675);
DISPLAY 0.680851 (-250 4675);
PAINT MONO (-250 4675);
DISPLAY INVISIBLE (-250 4675);
FORCEPROP 0 LAST CDS_SEC 1
J 0
(-250 4675);
DISPLAY 1.021277 (-250 4675);
DISPLAY INVISIBLE (-250 4675);
FORCEADD OFFPAGE..1
(-3950 4125);
PAINT AQUA (-3950 4125);
FORCEPROP 2 LAST $XR1 129 
J 0
(-4202 4089);
DISPLAY 0.638298 (-4202 4089);
PAINT MONO (-4202 4089);
FORCEPROP 2 LAST $XR0 216 
J 0
(-4202 4125);
DISPLAY 0.638298 (-4202 4125);
PAINT MONO (-4202 4125);
FORCEPROP 2 LAST PATH I5
J 0
(-4200 4200);
DISPLAY 1.021277 (-4200 4200);
DISPLAY INVISIBLE (-4200 4200);
FORCEPROP 2 LAST CDS_LIB standard
J 0
(-3950 4125);
DISPLAY INVISIBLE (-3950 4125);
FORCEPROP 1 LAST OFFPAGE TRUE
J 0
(-3625 4000);
DISPLAY 0.872340 (-3625 4000);
PAINT AQUA (-3625 4000);
DISPLAY INVISIBLE (-3625 4000);
FORCEPROP 1 LAST COMMENT_BODY TRUE
J 0
(-3825 4025);
DISPLAY 0.872340 (-3825 4025);
PAINT GREEN (-3825 4025);
DISPLAY INVISIBLE (-3825 4025);
FORCEADD Q_RES..1
(-475 2850);
FORCEPROP 1 LAST PART_NUMBER CS11302FB03
J 0
(-700 2950);
DISPLAY 0.638298 (-700 2950);
DISPLAY INVISIBLE (-700 2950);
FORCEPROP 1 LAST TOLERANCE 1%
J 0
(-250 2850);
DISPLAY 0.638298 (-250 2850);
FORCEPROP 1 LAST MATERIAL CHIP
J 0
(-625 2800);
DISPLAY 0.638298 (-625 2800);
FORCEPROP 1 LAST WATTAGE 1/16W
J 2
(-325 2800);
DISPLAY 0.638298 (-325 2800);
FORCEPROP 1 LAST VALUE 130
J 2
(-275 2850);
DISPLAY 0.638298 (-275 2850);
FORCEPROP 1 LAST PACK_TYPE 0402LF
J 0
(-175 2850);
DISPLAY 0.638298 (-175 2850);
FORCEPROP 1 LAST $LOCATION R3080
J 0
(-525 2900);
DISPLAY 0.978723 (-525 2900);
FORCEPROP 1 LASTPIN (-575 2850) $PN 1
J 0
(-563 2862);
DISPLAY 0.787234 (-563 2862);
PAINT MONO (-563 2862);
FORCEPROP 1 LASTPIN (-375 2850) $PN 2
J 0
(-413 2862);
DISPLAY 0.787234 (-413 2862);
PAINT MONO (-413 2862);
FORCEPROP 2 LAST CDS_LIB pure_quanta
J 0
(-475 2850);
DISPLAY INVISIBLE (-475 2850);
FORCEPROP 1 LAST PATH I50
J 0
(-525 3000);
DISPLAY 0.978723 (-525 3000);
PAINT WHITE (-525 3000);
DISPLAY INVISIBLE (-525 3000);
FORCEPROP 0 LAST CDS_LOCATION R3080
J 0
(-525 2950);
DISPLAY 1.021277 (-525 2950);
DISPLAY INVISIBLE (-525 2950);
FORCEPROP 0 LAST $SEC 1
J 0
(-525 2950);
DISPLAY 0.680851 (-525 2950);
PAINT MONO (-525 2950);
DISPLAY INVISIBLE (-525 2950);
FORCEPROP 0 LAST CDS_SEC 1
J 0
(-525 2950);
DISPLAY 1.021277 (-525 2950);
DISPLAY INVISIBLE (-525 2950);
FORCEADD Q_RES..1
(-500 1175);
FORCEPROP 1 LAST PART_NUMBER CS11302FB03
J 0
(-725 1275);
DISPLAY 0.638298 (-725 1275);
DISPLAY INVISIBLE (-725 1275);
FORCEPROP 1 LAST PACK_TYPE 0402LF
J 0
(-200 1175);
DISPLAY 0.638298 (-200 1175);
FORCEPROP 1 LAST MATERIAL CHIP
J 0
(-650 1125);
DISPLAY 0.638298 (-650 1125);
FORCEPROP 1 LAST VALUE 130
J 2
(-300 1175);
DISPLAY 0.638298 (-300 1175);
FORCEPROP 1 LAST TOLERANCE 1%
J 0
(-275 1175);
DISPLAY 0.638298 (-275 1175);
FORCEPROP 1 LAST WATTAGE 1/16W
J 2
(-350 1125);
DISPLAY 0.638298 (-350 1125);
FORCEPROP 1 LAST $LOCATION R3079
J 0
(-550 1225);
DISPLAY 0.978723 (-550 1225);
FORCEPROP 1 LASTPIN (-600 1175) $PN 1
J 0
(-588 1187);
DISPLAY 0.787234 (-588 1187);
PAINT MONO (-588 1187);
FORCEPROP 1 LASTPIN (-400 1175) $PN 2
J 0
(-438 1187);
DISPLAY 0.787234 (-438 1187);
PAINT MONO (-438 1187);
FORCEPROP 1 LAST PATH I51
J 0
(-550 1325);
DISPLAY 0.978723 (-550 1325);
PAINT WHITE (-550 1325);
DISPLAY INVISIBLE (-550 1325);
FORCEPROP 2 LAST CDS_LIB pure_quanta
J 0
(-500 1175);
DISPLAY INVISIBLE (-500 1175);
FORCEPROP 0 LAST CDS_LOCATION R3079
J 0
(-550 1275);
DISPLAY 1.021277 (-550 1275);
DISPLAY INVISIBLE (-550 1275);
FORCEPROP 0 LAST $SEC 1
J 0
(-550 1275);
DISPLAY 0.680851 (-550 1275);
PAINT MONO (-550 1275);
DISPLAY INVISIBLE (-550 1275);
FORCEPROP 0 LAST CDS_SEC 1
J 0
(-550 1275);
DISPLAY 1.021277 (-550 1275);
DISPLAY INVISIBLE (-550 1275);
FORCEADD Q_RES..1
(-350 -175);
FORCEPROP 1 LAST PART_NUMBER CS11302FB03
J 0
(-575 -75);
DISPLAY 0.638298 (-575 -75);
DISPLAY INVISIBLE (-575 -75);
FORCEPROP 1 LAST VALUE 130
J 2
(-150 -175);
DISPLAY 0.638298 (-150 -175);
FORCEPROP 1 LAST TOLERANCE 1%
J 0
(-125 -175);
DISPLAY 0.638298 (-125 -175);
FORCEPROP 1 LAST WATTAGE 1/16W
J 2
(-200 -225);
DISPLAY 0.638298 (-200 -225);
FORCEPROP 1 LAST PACK_TYPE 0402LF
J 0
(-50 -175);
DISPLAY 0.638298 (-50 -175);
FORCEPROP 1 LAST MATERIAL CHIP
J 0
(-500 -225);
DISPLAY 0.638298 (-500 -225);
FORCEPROP 1 LAST $LOCATION R3081
J 0
(-400 -125);
DISPLAY 0.978723 (-400 -125);
FORCEPROP 1 LASTPIN (-450 -175) $PN 1
J 0
(-438 -163);
DISPLAY 0.787234 (-438 -163);
PAINT MONO (-438 -163);
FORCEPROP 1 LASTPIN (-250 -175) $PN 2
J 0
(-288 -163);
DISPLAY 0.787234 (-288 -163);
PAINT MONO (-288 -163);
FORCEPROP 1 LAST PATH I52
J 0
(-400 -25);
DISPLAY 0.978723 (-400 -25);
PAINT WHITE (-400 -25);
DISPLAY INVISIBLE (-400 -25);
FORCEPROP 2 LAST CDS_LIB pure_quanta
J 0
(-350 -175);
DISPLAY INVISIBLE (-350 -175);
FORCEPROP 0 LAST CDS_LOCATION R3081
J 0
(-400 -75);
DISPLAY 1.021277 (-400 -75);
DISPLAY INVISIBLE (-400 -75);
FORCEPROP 0 LAST $SEC 1
J 0
(-400 -75);
DISPLAY 0.680851 (-400 -75);
PAINT MONO (-400 -75);
DISPLAY INVISIBLE (-400 -75);
FORCEPROP 0 LAST CDS_SEC 1
J 0
(-400 -75);
DISPLAY 1.021277 (-400 -75);
DISPLAY INVISIBLE (-400 -75);
FORCEADD Q_RES..1
(4100 3000);
FORCEPROP 1 LAST PART_NUMBER CS11302FB03
J 0
(3875 3100);
DISPLAY 0.638298 (3875 3100);
DISPLAY INVISIBLE (3875 3100);
FORCEPROP 1 LAST VALUE 130
J 2
(4300 3000);
DISPLAY 0.638298 (4300 3000);
FORCEPROP 1 LAST TOLERANCE 1%
J 0
(4325 3000);
DISPLAY 0.638298 (4325 3000);
FORCEPROP 1 LAST MATERIAL CHIP
J 0
(3950 2950);
DISPLAY 0.638298 (3950 2950);
FORCEPROP 1 LAST WATTAGE 1/16W
J 2
(4250 2950);
DISPLAY 0.638298 (4250 2950);
FORCEPROP 1 LAST PACK_TYPE 0402LF
J 0
(4400 3000);
DISPLAY 0.638298 (4400 3000);
FORCEPROP 1 LAST $LOCATION R3084
J 0
(4050 3050);
DISPLAY 0.978723 (4050 3050);
FORCEPROP 1 LASTPIN (4000 3000) $PN 1
J 0
(4012 3012);
DISPLAY 0.787234 (4012 3012);
PAINT MONO (4012 3012);
FORCEPROP 1 LASTPIN (4200 3000) $PN 2
J 0
(4162 3012);
DISPLAY 0.787234 (4162 3012);
PAINT MONO (4162 3012);
FORCEPROP 2 LAST CDS_LIB pure_quanta
J 0
(4100 3000);
DISPLAY INVISIBLE (4100 3000);
FORCEPROP 1 LAST PATH I53
J 0
(4050 3150);
DISPLAY 0.978723 (4050 3150);
PAINT WHITE (4050 3150);
DISPLAY INVISIBLE (4050 3150);
FORCEPROP 0 LAST CDS_LOCATION R3084
J 0
(4050 3100);
DISPLAY 1.021277 (4050 3100);
DISPLAY INVISIBLE (4050 3100);
FORCEPROP 0 LAST $SEC 1
J 0
(4050 3100);
DISPLAY 0.680851 (4050 3100);
PAINT MONO (4050 3100);
DISPLAY INVISIBLE (4050 3100);
FORCEPROP 0 LAST CDS_SEC 1
J 0
(4050 3100);
DISPLAY 1.021277 (4050 3100);
DISPLAY INVISIBLE (4050 3100);
FORCEADD Q_RES..1
(4000 4425);
FORCEPROP 1 LAST PART_NUMBER CS11302FB03
J 0
(3775 4525);
DISPLAY 0.638298 (3775 4525);
DISPLAY INVISIBLE (3775 4525);
FORCEPROP 1 LAST VALUE 130
J 2
(4200 4425);
DISPLAY 0.638298 (4200 4425);
FORCEPROP 1 LAST TOLERANCE 1%
J 0
(4225 4425);
DISPLAY 0.638298 (4225 4425);
FORCEPROP 1 LAST MATERIAL CHIP
J 0
(3850 4375);
DISPLAY 0.638298 (3850 4375);
FORCEPROP 1 LAST WATTAGE 1/16W
J 2
(4150 4375);
DISPLAY 0.638298 (4150 4375);
FORCEPROP 1 LAST PACK_TYPE 0402LF
J 0
(4300 4425);
DISPLAY 0.638298 (4300 4425);
FORCEPROP 1 LAST $LOCATION R3082
J 0
(3950 4475);
DISPLAY 0.978723 (3950 4475);
FORCEPROP 1 LASTPIN (3900 4425) $PN 1
J 0
(3912 4437);
DISPLAY 0.787234 (3912 4437);
PAINT MONO (3912 4437);
FORCEPROP 1 LASTPIN (4100 4425) $PN 2
J 0
(4062 4437);
DISPLAY 0.787234 (4062 4437);
PAINT MONO (4062 4437);
FORCEPROP 2 LAST CDS_LIB pure_quanta
J 0
(4000 4425);
DISPLAY INVISIBLE (4000 4425);
FORCEPROP 1 LAST PATH I54
J 0
(3950 4575);
DISPLAY 0.978723 (3950 4575);
PAINT WHITE (3950 4575);
DISPLAY INVISIBLE (3950 4575);
FORCEPROP 0 LAST CDS_LOCATION R3082
J 0
(3950 4525);
DISPLAY 1.021277 (3950 4525);
DISPLAY INVISIBLE (3950 4525);
FORCEPROP 0 LAST $SEC 1
J 0
(3950 4525);
DISPLAY 0.680851 (3950 4525);
PAINT MONO (3950 4525);
DISPLAY INVISIBLE (3950 4525);
FORCEPROP 0 LAST CDS_SEC 1
J 0
(3950 4525);
DISPLAY 1.021277 (3950 4525);
DISPLAY INVISIBLE (3950 4525);
FORCEADD UNIVERSAL_POWER..1
(4675 1425);
FORCEPROP 3 LASTPIN (4675 1375) SIG_NAME P3V3_AUX\g
J 0
(4685 1385);
DISPLAY 0.659574 (4685 1385);
PAINT MONO (4685 1385);
DISPLAY INVISIBLE (4685 1385);
FORCEPROP 1 LAST HDL_POWER P3V3_AUX
J 1
(4675 1475);
DISPLAY 0.723404 (4675 1475);
PAINT GREEN (4675 1475);
FORCEPROP 2 LAST CDS_LIB logical_power
J 0
(4675 1425);
DISPLAY INVISIBLE (4675 1425);
FORCEPROP 1 LAST PATH I55
J 0
(4725 1450);
DISPLAY 0.872340 (4725 1450);
PAINT AQUA (4725 1450);
DISPLAY INVISIBLE (4725 1450);
FORCEADD UNIVERSAL_POWER..1
(4800 75);
FORCEPROP 3 LASTPIN (4800 25) SIG_NAME P3V3_AUX\g
J 0
(4810 35);
DISPLAY 0.659574 (4810 35);
PAINT MONO (4810 35);
DISPLAY INVISIBLE (4810 35);
FORCEPROP 1 LAST HDL_POWER P3V3_AUX
J 1
(4800 125);
DISPLAY 0.723404 (4800 125);
PAINT GREEN (4800 125);
FORCEPROP 2 LAST CDS_LIB logical_power
J 0
(4800 75);
DISPLAY INVISIBLE (4800 75);
FORCEPROP 1 LAST PATH I56
J 0
(4850 100);
DISPLAY 0.872340 (4850 100);
PAINT AQUA (4850 100);
DISPLAY INVISIBLE (4850 100);
FORCEADD Q_RES..1
(4025 1250);
FORCEPROP 1 LAST PART_NUMBER CS11302FB03
J 0
(3800 1350);
DISPLAY 0.638298 (3800 1350);
DISPLAY INVISIBLE (3800 1350);
FORCEPROP 1 LAST VALUE 130
J 2
(4225 1250);
DISPLAY 0.638298 (4225 1250);
FORCEPROP 1 LAST TOLERANCE 1%
J 0
(4250 1250);
DISPLAY 0.638298 (4250 1250);
FORCEPROP 1 LAST MATERIAL CHIP
J 0
(3875 1200);
DISPLAY 0.638298 (3875 1200);
FORCEPROP 1 LAST WATTAGE 1/16W
J 2
(4175 1200);
DISPLAY 0.638298 (4175 1200);
FORCEPROP 1 LAST PACK_TYPE 0402LF
J 0
(4325 1250);
DISPLAY 0.638298 (4325 1250);
FORCEPROP 1 LAST $LOCATION R3083
J 0
(3975 1300);
DISPLAY 0.978723 (3975 1300);
FORCEPROP 1 LASTPIN (3925 1250) $PN 1
J 0
(3937 1262);
DISPLAY 0.787234 (3937 1262);
PAINT MONO (3937 1262);
FORCEPROP 1 LASTPIN (4125 1250) $PN 2
J 0
(4087 1262);
DISPLAY 0.787234 (4087 1262);
PAINT MONO (4087 1262);
FORCEPROP 2 LAST CDS_LIB pure_quanta
J 0
(4025 1250);
DISPLAY INVISIBLE (4025 1250);
FORCEPROP 1 LAST PATH I57
J 0
(3975 1400);
DISPLAY 0.978723 (3975 1400);
PAINT WHITE (3975 1400);
DISPLAY INVISIBLE (3975 1400);
FORCEPROP 0 LAST CDS_LOCATION R3083
J 0
(3975 1350);
DISPLAY 1.021277 (3975 1350);
DISPLAY INVISIBLE (3975 1350);
FORCEPROP 0 LAST $SEC 1
J 0
(3975 1350);
DISPLAY 0.680851 (3975 1350);
PAINT MONO (3975 1350);
DISPLAY INVISIBLE (3975 1350);
FORCEPROP 0 LAST CDS_SEC 1
J 0
(3975 1350);
DISPLAY 1.021277 (3975 1350);
DISPLAY INVISIBLE (3975 1350);
FORCEADD Q_LED..1
R 2
(2725 1250);
FORCEPROP 1 LAST PART_NUMBER BEBL0172Z00
J 0
(2625 1025);
DISPLAY 0.574468 (2625 1025);
PAINT GREEN (2625 1025);
DISPLAY INVISIBLE (2625 1025);
FORCEPROP 1 LAST MATERIAL IC
J 0
(2750 1075);
DISPLAY 0.723404 (2750 1075);
PAINT GREEN (2750 1075);
FORCEPROP 2 LAST MANUF_PN LTST-C281TBKT-5A
J 0
(2625 975);
DISPLAY 0.638298 (2625 975);
FORCEPROP 2 LAST COLOR LED_BLUE
J 0
(2625 1125);
DISPLAY 0.638298 (2625 1125);
FORCEPROP 0 LAST PACK_TYPE SMLF
J 0
(2625 1075);
DISPLAY 0.638298 (2625 1075);
FORCEPROP 1 LAST LOCATION D71
J 0
(2625 1175);
DISPLAY 0.723404 (2625 1175);
PAINT GREEN (2625 1175);
FORCEPROP 0 LASTPIN (2875 1250) $PN A
J 0
(2885 1260);
DISPLAY 0.808511 (2885 1260);
FORCEPROP 0 LASTPIN (2575 1250) $PN C
J 2
(2565 1260);
DISPLAY 0.808511 (2565 1260);
FORCEPROP 1 LAST NEEDS_NO_SIZE TRUE
J 2
(2747 1272);
DISPLAY 0.468085 (2747 1272);
PAINT GREEN (2747 1272);
DISPLAY INVISIBLE (2747 1272);
FORCEPROP 2 LAST CDS_LIB pure_quanta
J 0
(2725 1250);
DISPLAY INVISIBLE (2725 1250);
FORCEPROP 1 LAST PATH I58
J 2
(2600 1330);
DISPLAY 0.723404 (2600 1330);
PAINT GREEN (2600 1330);
DISPLAY INVISIBLE (2600 1330);
FORCEPROP 0 LAST $SEC 1
J 0
(2625 1225);
DISPLAY INVISIBLE (2625 1225);
FORCEPROP 0 LAST CDS_SEC 1
J 0
(2625 1225);
DISPLAY INVISIBLE (2625 1225);
FORCEADD UNIVERSAL_GND..1
(1700 625);
FORCEPROP 3 LASTPIN (1700 675) SIG_NAME GND\g
J 0
(1710 685);
DISPLAY 0.659574 (1710 685);
PAINT MONO (1710 685);
DISPLAY INVISIBLE (1710 685);
FORCEPROP 2 LAST CDS_LIB logical_power
J 0
(1700 625);
DISPLAY INVISIBLE (1700 625);
FORCEPROP 1 LAST HDL_POWER GND
J 1
(1725 550);
DISPLAY 0.872340 (1725 550);
PAINT GREEN (1725 550);
DISPLAY INVISIBLE (1725 550);
FORCEPROP 1 LAST PATH I59
J 0
(1775 625);
DISPLAY 0.872340 (1775 625);
PAINT AQUA (1775 625);
DISPLAY INVISIBLE (1775 625);
FORCEADD UNIVERSAL_GND..1
(-2625 -875);
FORCEPROP 3 LASTPIN (-2625 -825) SIG_NAME GND\g
J 0
(-2615 -815);
DISPLAY 0.659574 (-2615 -815);
PAINT MONO (-2615 -815);
DISPLAY INVISIBLE (-2615 -815);
FORCEPROP 1 LAST PATH I6
J 0
(-2550 -875);
DISPLAY 0.872340 (-2550 -875);
PAINT AQUA (-2550 -875);
DISPLAY INVISIBLE (-2550 -875);
FORCEPROP 1 LAST HDL_POWER GND
J 1
(-2600 -950);
DISPLAY 0.872340 (-2600 -950);
PAINT GREEN (-2600 -950);
DISPLAY INVISIBLE (-2600 -950);
FORCEPROP 2 LAST CDS_LIB logical_power
J 0
(-2625 -875);
DISPLAY INVISIBLE (-2625 -875);
FORCEADD OFFPAGE..1
(550 925);
PAINT AQUA (550 925);
FORCEPROP 2 LAST $XR1 130 
J 0
(178 925);
DISPLAY 0.638298 (178 925);
PAINT MONO (178 925);
FORCEPROP 2 LAST $XR0 216 
J 0
(298 925);
DISPLAY 0.638298 (298 925);
PAINT MONO (298 925);
FORCEPROP 2 LAST CDS_LIB standard
J 0
(550 925);
DISPLAY INVISIBLE (550 925);
FORCEPROP 1 LAST OFFPAGE TRUE
J 0
(875 800);
DISPLAY 0.872340 (875 800);
PAINT AQUA (875 800);
DISPLAY INVISIBLE (875 800);
FORCEPROP 1 LAST COMMENT_BODY TRUE
J 0
(675 825);
DISPLAY 0.872340 (675 825);
PAINT GREEN (675 825);
DISPLAY INVISIBLE (675 825);
FORCEPROP 2 LAST PATH I61
J 0
(300 1050);
DISPLAY 1.021277 (300 1050);
DISPLAY INVISIBLE (300 1050);
FORCEADD Q_RES..1
(4175 -100);
FORCEPROP 1 LAST PART_NUMBER CS11302FB03
J 0
(3950 0);
DISPLAY 0.638298 (3950 0);
DISPLAY INVISIBLE (3950 0);
FORCEPROP 1 LAST MATERIAL CHIP
J 0
(4025 -150);
DISPLAY 0.638298 (4025 -150);
FORCEPROP 1 LAST PACK_TYPE 0402LF
J 0
(4475 -100);
DISPLAY 0.638298 (4475 -100);
FORCEPROP 1 LAST WATTAGE 1/16W
J 2
(4325 -150);
DISPLAY 0.638298 (4325 -150);
FORCEPROP 1 LAST TOLERANCE 1%
J 0
(4400 -100);
DISPLAY 0.638298 (4400 -100);
FORCEPROP 1 LAST VALUE 130
J 2
(4375 -100);
DISPLAY 0.638298 (4375 -100);
FORCEPROP 1 LAST $LOCATION R3085
J 0
(4125 -50);
DISPLAY 0.978723 (4125 -50);
FORCEPROP 1 LASTPIN (4075 -100) $PN 1
J 0
(4087 -88);
DISPLAY 0.787234 (4087 -88);
PAINT MONO (4087 -88);
FORCEPROP 1 LASTPIN (4275 -100) $PN 2
J 0
(4237 -88);
DISPLAY 0.787234 (4237 -88);
PAINT MONO (4237 -88);
FORCEPROP 2 LAST CDS_LIB pure_quanta
J 0
(4175 -100);
DISPLAY INVISIBLE (4175 -100);
FORCEPROP 1 LAST PATH I62
J 0
(4125 50);
DISPLAY 0.978723 (4125 50);
PAINT WHITE (4125 50);
DISPLAY INVISIBLE (4125 50);
FORCEPROP 0 LAST CDS_LOCATION R3085
J 0
(4125 0);
DISPLAY 1.021277 (4125 0);
DISPLAY INVISIBLE (4125 0);
FORCEPROP 0 LAST $SEC 1
J 0
(4125 0);
DISPLAY 0.680851 (4125 0);
PAINT MONO (4125 0);
DISPLAY INVISIBLE (4125 0);
FORCEPROP 0 LAST CDS_SEC 1
J 0
(4125 0);
DISPLAY 1.021277 (4125 0);
DISPLAY INVISIBLE (4125 0);
FORCEADD Q_LED..1
R 2
(2875 -100);
FORCEPROP 1 LAST PART_NUMBER BEBL0172Z00
J 0
(2775 -325);
DISPLAY 0.574468 (2775 -325);
PAINT GREEN (2775 -325);
DISPLAY INVISIBLE (2775 -325);
FORCEPROP 1 LAST MATERIAL IC
J 0
(2900 -275);
DISPLAY 0.723404 (2900 -275);
PAINT GREEN (2900 -275);
FORCEPROP 2 LAST COLOR LED_BLUE
J 0
(2775 -225);
DISPLAY 0.638298 (2775 -225);
FORCEPROP 0 LAST PACK_TYPE SMLF
J 0
(2775 -275);
DISPLAY 0.638298 (2775 -275);
FORCEPROP 2 LAST MANUF_PN LTST-C281TBKT-5A
J 0
(2775 -375);
DISPLAY 0.638298 (2775 -375);
FORCEPROP 1 LAST LOCATION D72
J 0
(2775 -175);
DISPLAY 0.723404 (2775 -175);
PAINT GREEN (2775 -175);
FORCEPROP 0 LASTPIN (3025 -100) $PN A
J 0
(3035 -90);
DISPLAY 0.808511 (3035 -90);
FORCEPROP 0 LASTPIN (2725 -100) $PN C
J 2
(2715 -90);
DISPLAY 0.808511 (2715 -90);
FORCEPROP 1 LAST NEEDS_NO_SIZE TRUE
J 2
(2897 -78);
DISPLAY 0.468085 (2897 -78);
PAINT GREEN (2897 -78);
DISPLAY INVISIBLE (2897 -78);
FORCEPROP 2 LAST CDS_LIB pure_quanta
J 0
(2875 -100);
DISPLAY INVISIBLE (2875 -100);
FORCEPROP 1 LAST PATH I63
J 2
(2750 -20);
DISPLAY 0.723404 (2750 -20);
PAINT GREEN (2750 -20);
DISPLAY INVISIBLE (2750 -20);
FORCEPROP 0 LAST $SEC 1
J 0
(2775 -125);
DISPLAY INVISIBLE (2775 -125);
FORCEPROP 0 LAST CDS_SEC 1
J 0
(2775 -125);
DISPLAY INVISIBLE (2775 -125);
FORCEADD UNIVERSAL_GND..1
(1900 -800);
FORCEPROP 3 LASTPIN (1900 -750) SIG_NAME GND\g
J 0
(1910 -740);
DISPLAY 0.659574 (1910 -740);
PAINT MONO (1910 -740);
DISPLAY INVISIBLE (1910 -740);
FORCEPROP 2 LAST CDS_LIB logical_power
J 0
(1900 -800);
DISPLAY INVISIBLE (1900 -800);
FORCEPROP 1 LAST HDL_POWER GND
J 1
(1925 -875);
DISPLAY 0.872340 (1925 -875);
PAINT GREEN (1925 -875);
DISPLAY INVISIBLE (1925 -875);
FORCEPROP 1 LAST PATH I64
J 0
(1975 -800);
DISPLAY 0.872340 (1975 -800);
PAINT AQUA (1975 -800);
DISPLAY INVISIBLE (1975 -800);
FORCEADD OFFPAGE..1
(700 -425);
PAINT AQUA (700 -425);
FORCEPROP 2 LAST $XR1 130 
J 0
(298 -425);
DISPLAY 0.638298 (298 -425);
PAINT MONO (298 -425);
FORCEPROP 2 LAST $XR0 216 
J 0
(418 -425);
DISPLAY 0.638298 (418 -425);
PAINT MONO (418 -425);
FORCEPROP 2 LAST CDS_LIB standard
J 0
(700 -425);
DISPLAY INVISIBLE (700 -425);
FORCEPROP 1 LAST OFFPAGE TRUE
J 0
(1025 -550);
DISPLAY 0.872340 (1025 -550);
PAINT AQUA (1025 -550);
DISPLAY INVISIBLE (1025 -550);
FORCEPROP 1 LAST COMMENT_BODY TRUE
J 0
(825 -525);
DISPLAY 0.872340 (825 -525);
PAINT GREEN (825 -525);
DISPLAY INVISIBLE (825 -525);
FORCEPROP 2 LAST PATH I66
J 0
(425 -375);
DISPLAY 1.021277 (425 -375);
DISPLAY INVISIBLE (425 -375);
FORCEADD UNIVERSAL_GND..1
(1675 2400);
FORCEPROP 3 LASTPIN (1675 2450) SIG_NAME GND\g
J 0
(1685 2460);
DISPLAY 0.659574 (1685 2460);
PAINT MONO (1685 2460);
DISPLAY INVISIBLE (1685 2460);
FORCEPROP 1 LAST HDL_POWER GND
J 1
(1700 2325);
DISPLAY 0.872340 (1700 2325);
PAINT GREEN (1700 2325);
DISPLAY INVISIBLE (1700 2325);
FORCEPROP 1 LAST PATH I67
J 0
(1750 2400);
DISPLAY 0.872340 (1750 2400);
PAINT AQUA (1750 2400);
DISPLAY INVISIBLE (1750 2400);
FORCEPROP 2 LAST CDS_LIB logical_power
J 0
(1675 2400);
DISPLAY INVISIBLE (1675 2400);
FORCEADD MOSFET_NCH_DUAL..1
(-2850 4175);
FORCEPROP 1 LAST PART_NUMBER BAM60080000
J 0
(-2699 4089);
DISPLAY 0.723404 (-2699 4089);
PAINT GREEN (-2699 4089);
DISPLAY INVISIBLE (-2699 4089);
FORCEPROP 2 LAST PART_TYPE SMLF
J 0
(-2675 4250);
DISPLAY 1.021277 (-2675 4250);
FORCEPROP 1 LAST MATERIAL IC
J 0
(-2699 4024);
DISPLAY 0.723404 (-2699 4024);
PAINT GREEN (-2699 4024);
FORCEPROP 2 LAST VALUE NX6008NBKS
J 0
(-2675 4200);
DISPLAY 1.021277 (-2675 4200);
FORCEPROP 1 LAST $LOCATION Q98
J 0
(-2699 4149);
DISPLAY 0.723404 (-2699 4149);
PAINT GREEN (-2699 4149);
FORCEPROP 0 LASTPIN (-2800 4375) $PN 6
R 1
J 0
(-2810 4385);
DISPLAY 0.680851 (-2810 4385);
PAINT MONO (-2810 4385);
FORCEPROP 0 LASTPIN (-3050 4125) $PN 2
J 2
(-3060 4135);
DISPLAY 0.680851 (-3060 4135);
PAINT MONO (-3060 4135);
FORCEPROP 0 LASTPIN (-2800 3975) $PN 1
R 1
J 2
(-2810 3965);
DISPLAY 0.680851 (-2810 3965);
PAINT MONO (-2810 3965);
FORCEPROP 2 LAST CDS_LIB pure_quanta
J 0
(-2850 4175);
DISPLAY INVISIBLE (-2850 4175);
FORCEPROP 1 LAST CDS_LMAN_SYM_OUTLINE -150,150,150,-150
J 0
(-2850 4175);
DISPLAY 0.468085 (-2850 4175);
PAINT GREEN (-2850 4175);
DISPLAY INVISIBLE (-2850 4175);
FORCEPROP 1 LAST PATH I68
J 0
(-2850 4175);
DISPLAY 0.723404 (-2850 4175);
PAINT GREEN (-2850 4175);
DISPLAY INVISIBLE (-2850 4175);
FORCEPROP 1 LAST NEEDS_NO_SIZE TRUE
J 0
(-2850 4174);
DISPLAY 0.468085 (-2850 4174);
PAINT GREEN (-2850 4174);
DISPLAY INVISIBLE (-2850 4174);
FORCEPROP 0 LAST CDS_LOCATION Q98
J 0
(-2675 4300);
DISPLAY 1.021277 (-2675 4300);
DISPLAY INVISIBLE (-2675 4300);
FORCEPROP 0 LAST $SEC 1
J 0
(-2675 4300);
DISPLAY 0.680851 (-2675 4300);
PAINT MONO (-2675 4300);
DISPLAY INVISIBLE (-2675 4300);
FORCEPROP 0 LAST CDS_SEC 1
J 0
(-2675 4300);
DISPLAY 1.021277 (-2675 4300);
DISPLAY INVISIBLE (-2675 4300);
FORCEADD MOSFET_NCH_DUAL..2
(-2850 2575);
FORCEPROP 1 LAST PART_NUMBER BAM60080000
J 0
(-2699 2481);
DISPLAY 0.723404 (-2699 2481);
PAINT GREEN (-2699 2481);
DISPLAY INVISIBLE (-2699 2481);
FORCEPROP 1 LAST MATERIAL IC
J 0
(-2699 2426);
DISPLAY 0.723404 (-2699 2426);
PAINT GREEN (-2699 2426);
FORCEPROP 2 LAST PART_TYPE SMLF
J 0
(-2675 2650);
DISPLAY 1.021277 (-2675 2650);
FORCEPROP 2 LAST VALUE NX6008NBKS
J 0
(-2675 2600);
DISPLAY 1.021277 (-2675 2600);
FORCEPROP 1 LAST $LOCATION Q98
J 0
(-2699 2551);
DISPLAY 0.723404 (-2699 2551);
PAINT GREEN (-2699 2551);
FORCEPROP 0 LASTPIN (-2800 2775) $PN 3
R 1
J 0
(-2810 2785);
DISPLAY 0.680851 (-2810 2785);
PAINT MONO (-2810 2785);
FORCEPROP 0 LASTPIN (-3050 2525) $PN 5
J 2
(-3060 2535);
DISPLAY 0.680851 (-3060 2535);
PAINT MONO (-3060 2535);
FORCEPROP 0 LASTPIN (-2800 2375) $PN 4
R 1
J 2
(-2810 2365);
DISPLAY 0.680851 (-2810 2365);
PAINT MONO (-2810 2365);
FORCEPROP 2 LAST CDS_LIB pure_quanta
J 0
(-2850 2575);
DISPLAY INVISIBLE (-2850 2575);
FORCEPROP 1 LAST CDS_LMAN_SYM_OUTLINE -150,150,150,-150
J 0
(-2850 2575);
DISPLAY 0.468085 (-2850 2575);
PAINT GREEN (-2850 2575);
DISPLAY INVISIBLE (-2850 2575);
FORCEPROP 1 LAST PATH I69
J 0
(-2700 2425);
DISPLAY 0.723404 (-2700 2425);
PAINT GREEN (-2700 2425);
DISPLAY INVISIBLE (-2700 2425);
FORCEPROP 1 LAST NEEDS_NO_SIZE TRUE
J 0
(-2700 2466);
DISPLAY 0.468085 (-2700 2466);
PAINT GREEN (-2700 2466);
DISPLAY INVISIBLE (-2700 2466);
FORCEPROP 0 LAST CDS_LOCATION Q98
J 0
(-2675 2700);
DISPLAY 1.021277 (-2675 2700);
DISPLAY INVISIBLE (-2675 2700);
FORCEPROP 0 LAST $SEC 2
J 0
(-2675 2700);
DISPLAY 0.680851 (-2675 2700);
PAINT MONO (-2675 2700);
DISPLAY INVISIBLE (-2675 2700);
FORCEPROP 0 LAST CDS_SEC 2
J 0
(-2675 2700);
DISPLAY 1.021277 (-2675 2700);
DISPLAY INVISIBLE (-2675 2700);
FORCEADD MOSFET_NCH_DUAL..2
(-2675 -450);
FORCEPROP 1 LAST PART_NUMBER BAM60080000
J 0
(-2524 -544);
DISPLAY 0.723404 (-2524 -544);
PAINT GREEN (-2524 -544);
DISPLAY INVISIBLE (-2524 -544);
FORCEPROP 1 LAST MATERIAL IC
J 0
(-2524 -599);
DISPLAY 0.723404 (-2524 -599);
PAINT GREEN (-2524 -599);
FORCEPROP 2 LAST VALUE NX6008NBKS
J 0
(-2500 -425);
DISPLAY 1.021277 (-2500 -425);
FORCEPROP 2 LAST PART_TYPE SMLF
J 0
(-2500 -375);
DISPLAY 1.021277 (-2500 -375);
FORCEPROP 1 LAST $LOCATION Q97
J 0
(-2524 -474);
DISPLAY 0.723404 (-2524 -474);
PAINT GREEN (-2524 -474);
FORCEPROP 0 LASTPIN (-2625 -250) $PN 3
R 1
J 0
(-2635 -240);
DISPLAY 0.680851 (-2635 -240);
PAINT MONO (-2635 -240);
FORCEPROP 0 LASTPIN (-2875 -500) $PN 5
J 2
(-2885 -490);
DISPLAY 0.680851 (-2885 -490);
PAINT MONO (-2885 -490);
FORCEPROP 0 LASTPIN (-2625 -650) $PN 4
R 1
J 2
(-2635 -660);
DISPLAY 0.680851 (-2635 -660);
PAINT MONO (-2635 -660);
FORCEPROP 2 LAST CDS_LIB pure_quanta
J 0
(-2675 -450);
DISPLAY INVISIBLE (-2675 -450);
FORCEPROP 1 LAST PATH I70
J 0
(-2525 -600);
DISPLAY 0.723404 (-2525 -600);
PAINT GREEN (-2525 -600);
DISPLAY INVISIBLE (-2525 -600);
FORCEPROP 1 LAST CDS_LMAN_SYM_OUTLINE -150,150,150,-150
J 0
(-2675 -450);
DISPLAY 0.468085 (-2675 -450);
PAINT GREEN (-2675 -450);
DISPLAY INVISIBLE (-2675 -450);
FORCEPROP 1 LAST NEEDS_NO_SIZE TRUE
J 0
(-2525 -559);
DISPLAY 0.468085 (-2525 -559);
PAINT GREEN (-2525 -559);
DISPLAY INVISIBLE (-2525 -559);
FORCEPROP 0 LAST CDS_LOCATION Q97
J 0
(-2500 -325);
DISPLAY 1.021277 (-2500 -325);
DISPLAY INVISIBLE (-2500 -325);
FORCEPROP 0 LAST $SEC 2
J 0
(-2500 -325);
DISPLAY 0.680851 (-2500 -325);
PAINT MONO (-2500 -325);
DISPLAY INVISIBLE (-2500 -325);
FORCEPROP 0 LAST CDS_SEC 2
J 0
(-2500 -325);
DISPLAY 1.021277 (-2500 -325);
DISPLAY INVISIBLE (-2500 -325);
FORCEADD MOSFET_NCH_DUAL..1
(-2875 900);
FORCEPROP 1 LAST PART_NUMBER BAM60080000
J 0
(-2724 814);
DISPLAY 0.723404 (-2724 814);
PAINT GREEN (-2724 814);
DISPLAY INVISIBLE (-2724 814);
FORCEPROP 2 LAST PART_TYPE SMLF
J 0
(-2700 975);
DISPLAY 1.021277 (-2700 975);
FORCEPROP 2 LAST VALUE NX6008NBKS
J 0
(-2700 925);
DISPLAY 1.021277 (-2700 925);
FORCEPROP 1 LAST MATERIAL IC
J 0
(-2724 749);
DISPLAY 0.723404 (-2724 749);
PAINT GREEN (-2724 749);
FORCEPROP 1 LAST $LOCATION Q97
J 0
(-2724 874);
DISPLAY 0.723404 (-2724 874);
PAINT GREEN (-2724 874);
FORCEPROP 0 LASTPIN (-2825 1100) $PN 6
R 1
J 0
(-2835 1110);
DISPLAY 0.680851 (-2835 1110);
PAINT MONO (-2835 1110);
FORCEPROP 0 LASTPIN (-3075 850) $PN 2
J 2
(-3085 860);
DISPLAY 0.680851 (-3085 860);
PAINT MONO (-3085 860);
FORCEPROP 0 LASTPIN (-2825 700) $PN 1
R 1
J 2
(-2835 690);
DISPLAY 0.680851 (-2835 690);
PAINT MONO (-2835 690);
FORCEPROP 1 LAST NEEDS_NO_SIZE TRUE
J 0
(-2875 899);
DISPLAY 0.468085 (-2875 899);
PAINT GREEN (-2875 899);
DISPLAY INVISIBLE (-2875 899);
FORCEPROP 1 LAST CDS_LMAN_SYM_OUTLINE -150,150,150,-150
J 0
(-2875 900);
DISPLAY 0.468085 (-2875 900);
PAINT GREEN (-2875 900);
DISPLAY INVISIBLE (-2875 900);
FORCEPROP 1 LAST PATH I71
J 0
(-2875 900);
DISPLAY 0.723404 (-2875 900);
PAINT GREEN (-2875 900);
DISPLAY INVISIBLE (-2875 900);
FORCEPROP 2 LAST CDS_LIB pure_quanta
J 0
(-2875 900);
DISPLAY INVISIBLE (-2875 900);
FORCEPROP 0 LAST CDS_LOCATION Q97
J 0
(-2700 1025);
DISPLAY 1.021277 (-2700 1025);
DISPLAY INVISIBLE (-2700 1025);
FORCEPROP 0 LAST $SEC 1
J 0
(-2700 1025);
DISPLAY 0.680851 (-2700 1025);
PAINT MONO (-2700 1025);
DISPLAY INVISIBLE (-2700 1025);
FORCEPROP 0 LAST CDS_SEC 1
J 0
(-2700 1025);
DISPLAY 1.021277 (-2700 1025);
DISPLAY INVISIBLE (-2700 1025);
FORCEADD MOSFET_NCH_DUAL..1
(1625 2725);
FORCEPROP 1 LAST PART_NUMBER BAM60080000
J 0
(1776 2639);
DISPLAY 0.723404 (1776 2639);
PAINT GREEN (1776 2639);
DISPLAY INVISIBLE (1776 2639);
FORCEPROP 2 LAST PART_TYPE SMLF
J 0
(1800 2800);
DISPLAY 1.021277 (1800 2800);
FORCEPROP 1 LAST MATERIAL IC
J 0
(1776 2574);
DISPLAY 0.723404 (1776 2574);
PAINT GREEN (1776 2574);
FORCEPROP 2 LAST VALUE NX6008NBKS
J 0
(1800 2750);
DISPLAY 1.021277 (1800 2750);
FORCEPROP 1 LAST $LOCATION Q99
J 0
(1776 2699);
DISPLAY 0.723404 (1776 2699);
PAINT GREEN (1776 2699);
FORCEPROP 0 LASTPIN (1675 2925) $PN 6
R 1
J 0
(1665 2935);
DISPLAY 0.680851 (1665 2935);
PAINT MONO (1665 2935);
FORCEPROP 0 LASTPIN (1425 2675) $PN 2
J 2
(1415 2685);
DISPLAY 0.680851 (1415 2685);
PAINT MONO (1415 2685);
FORCEPROP 0 LASTPIN (1675 2525) $PN 1
R 1
J 2
(1665 2515);
DISPLAY 0.680851 (1665 2515);
PAINT MONO (1665 2515);
FORCEPROP 2 LAST CDS_LIB pure_quanta
J 0
(1625 2725);
DISPLAY INVISIBLE (1625 2725);
FORCEPROP 1 LAST CDS_LMAN_SYM_OUTLINE -150,150,150,-150
J 0
(1625 2725);
DISPLAY 0.468085 (1625 2725);
PAINT GREEN (1625 2725);
DISPLAY INVISIBLE (1625 2725);
FORCEPROP 1 LAST PATH I72
J 0
(1625 2725);
DISPLAY 0.723404 (1625 2725);
PAINT GREEN (1625 2725);
DISPLAY INVISIBLE (1625 2725);
FORCEPROP 1 LAST NEEDS_NO_SIZE TRUE
J 0
(1625 2724);
DISPLAY 0.468085 (1625 2724);
PAINT GREEN (1625 2724);
DISPLAY INVISIBLE (1625 2724);
FORCEPROP 0 LAST CDS_LOCATION Q99
J 0
(1800 2850);
DISPLAY 1.021277 (1800 2850);
DISPLAY INVISIBLE (1800 2850);
FORCEPROP 0 LAST $SEC 1
J 0
(1800 2850);
DISPLAY 0.680851 (1800 2850);
PAINT MONO (1800 2850);
DISPLAY INVISIBLE (1800 2850);
FORCEPROP 0 LAST CDS_SEC 1
J 0
(1800 2850);
DISPLAY 1.021277 (1800 2850);
DISPLAY INVISIBLE (1800 2850);
FORCEADD MOSFET_NCH_DUAL..1
(1650 975);
FORCEPROP 1 LAST PART_NUMBER BAM60080000
J 0
(1801 889);
DISPLAY 0.723404 (1801 889);
PAINT GREEN (1801 889);
DISPLAY INVISIBLE (1801 889);
FORCEPROP 2 LAST PART_TYPE SMLF
J 0
(1825 1050);
DISPLAY 1.021277 (1825 1050);
FORCEPROP 2 LAST VALUE NX6008NBKS
J 0
(1825 1000);
DISPLAY 1.021277 (1825 1000);
FORCEPROP 1 LAST MATERIAL IC
J 0
(1801 824);
DISPLAY 0.723404 (1801 824);
PAINT GREEN (1801 824);
FORCEPROP 1 LAST $LOCATION Q100
J 0
(1801 949);
DISPLAY 0.723404 (1801 949);
PAINT GREEN (1801 949);
FORCEPROP 0 LASTPIN (1700 1175) $PN 6
R 1
J 0
(1690 1185);
DISPLAY 0.680851 (1690 1185);
PAINT MONO (1690 1185);
FORCEPROP 0 LASTPIN (1450 925) $PN 2
J 2
(1440 935);
DISPLAY 0.680851 (1440 935);
PAINT MONO (1440 935);
FORCEPROP 0 LASTPIN (1700 775) $PN 1
R 1
J 2
(1690 765);
DISPLAY 0.680851 (1690 765);
PAINT MONO (1690 765);
FORCEPROP 1 LAST NEEDS_NO_SIZE TRUE
J 0
(1650 974);
DISPLAY 0.468085 (1650 974);
PAINT GREEN (1650 974);
DISPLAY INVISIBLE (1650 974);
FORCEPROP 1 LAST CDS_LMAN_SYM_OUTLINE -150,150,150,-150
J 0
(1650 975);
DISPLAY 0.468085 (1650 975);
PAINT GREEN (1650 975);
DISPLAY INVISIBLE (1650 975);
FORCEPROP 1 LAST PATH I74
J 0
(1650 975);
DISPLAY 0.723404 (1650 975);
PAINT GREEN (1650 975);
DISPLAY INVISIBLE (1650 975);
FORCEPROP 2 LAST CDS_LIB pure_quanta
J 0
(1650 975);
DISPLAY INVISIBLE (1650 975);
FORCEPROP 0 LAST CDS_LOCATION Q100
J 0
(1825 1100);
DISPLAY 1.021277 (1825 1100);
DISPLAY INVISIBLE (1825 1100);
FORCEPROP 0 LAST $SEC 1
J 0
(1825 1100);
DISPLAY 0.680851 (1825 1100);
PAINT MONO (1825 1100);
DISPLAY INVISIBLE (1825 1100);
FORCEPROP 0 LAST CDS_SEC 1
J 0
(1825 1100);
DISPLAY 1.021277 (1825 1100);
DISPLAY INVISIBLE (1825 1100);
FORCEADD MOSFET_NCH_DUAL..2
(1850 -375);
FORCEPROP 1 LAST PART_NUMBER BAM60080000
J 0
(2001 -469);
DISPLAY 0.723404 (2001 -469);
PAINT GREEN (2001 -469);
DISPLAY INVISIBLE (2001 -469);
FORCEPROP 2 LAST PART_TYPE SMLF
J 0
(2025 -300);
DISPLAY 1.021277 (2025 -300);
FORCEPROP 1 LAST MATERIAL IC
J 0
(2001 -524);
DISPLAY 0.723404 (2001 -524);
PAINT GREEN (2001 -524);
FORCEPROP 2 LAST VALUE NX6008NBKS
J 0
(2025 -350);
DISPLAY 1.021277 (2025 -350);
FORCEPROP 1 LAST $LOCATION Q100
J 0
(2001 -399);
DISPLAY 0.723404 (2001 -399);
PAINT GREEN (2001 -399);
FORCEPROP 0 LASTPIN (1900 -175) $PN 3
R 1
J 0
(1890 -165);
DISPLAY 0.680851 (1890 -165);
PAINT MONO (1890 -165);
FORCEPROP 0 LASTPIN (1650 -425) $PN 5
J 2
(1640 -415);
DISPLAY 0.680851 (1640 -415);
PAINT MONO (1640 -415);
FORCEPROP 0 LASTPIN (1900 -575) $PN 4
R 1
J 2
(1890 -585);
DISPLAY 0.680851 (1890 -585);
PAINT MONO (1890 -585);
FORCEPROP 2 LAST CDS_LIB pure_quanta
J 0
(1850 -375);
DISPLAY INVISIBLE (1850 -375);
FORCEPROP 1 LAST PATH I75
J 0
(2000 -525);
DISPLAY 0.723404 (2000 -525);
PAINT GREEN (2000 -525);
DISPLAY INVISIBLE (2000 -525);
FORCEPROP 1 LAST CDS_LMAN_SYM_OUTLINE -150,150,150,-150
J 0
(1850 -375);
DISPLAY 0.468085 (1850 -375);
PAINT GREEN (1850 -375);
DISPLAY INVISIBLE (1850 -375);
FORCEPROP 1 LAST NEEDS_NO_SIZE TRUE
J 0
(2000 -484);
DISPLAY 0.468085 (2000 -484);
PAINT GREEN (2000 -484);
DISPLAY INVISIBLE (2000 -484);
FORCEPROP 0 LAST CDS_LOCATION Q100
J 0
(2025 -250);
DISPLAY 1.021277 (2025 -250);
DISPLAY INVISIBLE (2025 -250);
FORCEPROP 0 LAST $SEC 2
J 0
(2025 -250);
DISPLAY 0.680851 (2025 -250);
PAINT MONO (2025 -250);
DISPLAY INVISIBLE (2025 -250);
FORCEPROP 0 LAST CDS_SEC 2
J 0
(2025 -250);
DISPLAY 1.021277 (2025 -250);
DISPLAY INVISIBLE (2025 -250);
FORCEADD MOSFET_NCH_DUAL..1
(1625 4150);
FORCEPROP 1 LAST PART_NUMBER BAM60080000
J 0
(1776 4064);
DISPLAY 0.723404 (1776 4064);
PAINT GREEN (1776 4064);
DISPLAY INVISIBLE (1776 4064);
FORCEPROP 2 LAST PART_TYPE SMLF
J 0
(1800 4225);
DISPLAY 1.021277 (1800 4225);
FORCEPROP 1 LAST MATERIAL IC
J 0
(1776 3999);
DISPLAY 0.723404 (1776 3999);
PAINT GREEN (1776 3999);
FORCEPROP 2 LAST VALUE NX6008NBKS
J 0
(1800 4175);
DISPLAY 1.021277 (1800 4175);
FORCEPROP 1 LAST $LOCATION Q105
J 0
(1776 4124);
DISPLAY 0.723404 (1776 4124);
PAINT GREEN (1776 4124);
FORCEPROP 0 LASTPIN (1675 4350) $PN 6
R 1
J 0
(1665 4360);
DISPLAY 0.680851 (1665 4360);
PAINT MONO (1665 4360);
FORCEPROP 0 LASTPIN (1425 4100) $PN 2
J 2
(1415 4110);
DISPLAY 0.680851 (1415 4110);
PAINT MONO (1415 4110);
FORCEPROP 0 LASTPIN (1675 3950) $PN 1
R 1
J 2
(1665 3940);
DISPLAY 0.680851 (1665 3940);
PAINT MONO (1665 3940);
FORCEPROP 1 LAST NEEDS_NO_SIZE TRUE
J 0
(1625 4149);
DISPLAY 0.468085 (1625 4149);
PAINT GREEN (1625 4149);
DISPLAY INVISIBLE (1625 4149);
FORCEPROP 1 LAST CDS_LMAN_SYM_OUTLINE -150,150,150,-150
J 0
(1625 4150);
DISPLAY 0.468085 (1625 4150);
PAINT GREEN (1625 4150);
DISPLAY INVISIBLE (1625 4150);
FORCEPROP 1 LAST PATH I76
J 0
(1625 4150);
DISPLAY 0.723404 (1625 4150);
PAINT GREEN (1625 4150);
DISPLAY INVISIBLE (1625 4150);
FORCEPROP 2 LAST CDS_LIB pure_quanta
J 0
(1625 4150);
DISPLAY INVISIBLE (1625 4150);
FORCEPROP 0 LAST CDS_LOCATION Q105
J 0
(1800 4275);
DISPLAY 1.021277 (1800 4275);
DISPLAY INVISIBLE (1800 4275);
FORCEPROP 0 LAST $SEC 1
J 0
(1800 4275);
DISPLAY 0.680851 (1800 4275);
PAINT MONO (1800 4275);
DISPLAY INVISIBLE (1800 4275);
FORCEPROP 0 LAST CDS_SEC 1
J 0
(1800 4275);
DISPLAY 1.021277 (1800 4275);
DISPLAY INVISIBLE (1800 4275);
FORCEADD UNIVERSAL_GND..1
(-2825 550);
FORCEPROP 3 LASTPIN (-2825 600) SIG_NAME GND\g
J 0
(-2815 610);
DISPLAY 0.659574 (-2815 610);
PAINT MONO (-2815 610);
DISPLAY INVISIBLE (-2815 610);
FORCEPROP 1 LAST PATH I8
J 0
(-2750 550);
DISPLAY 0.872340 (-2750 550);
PAINT AQUA (-2750 550);
DISPLAY INVISIBLE (-2750 550);
FORCEPROP 1 LAST HDL_POWER GND
J 1
(-2800 475);
DISPLAY 0.872340 (-2800 475);
PAINT GREEN (-2800 475);
DISPLAY INVISIBLE (-2800 475);
FORCEPROP 2 LAST CDS_LIB logical_power
J 0
(-2825 550);
DISPLAY INVISIBLE (-2825 550);
FORCEADD Q_LED..1
R 2
(-1650 -175);
FORCEPROP 1 LAST PART_NUMBER BEBL0172Z00
J 0
(-1750 -400);
DISPLAY 0.574468 (-1750 -400);
PAINT GREEN (-1750 -400);
DISPLAY INVISIBLE (-1750 -400);
FORCEPROP 0 LAST PACK_TYPE SMLF
J 0
(-1750 -350);
DISPLAY 0.638298 (-1750 -350);
FORCEPROP 1 LAST MATERIAL IC
J 0
(-1625 -350);
DISPLAY 0.723404 (-1625 -350);
PAINT GREEN (-1625 -350);
FORCEPROP 2 LAST COLOR LED_BLUE
J 0
(-1750 -300);
DISPLAY 0.638298 (-1750 -300);
FORCEPROP 2 LAST MANUF_PN LTST-C281TBKT-5A
J 0
(-1750 -450);
DISPLAY 0.638298 (-1750 -450);
FORCEPROP 1 LAST LOCATION D68
J 0
(-1750 -250);
DISPLAY 0.723404 (-1750 -250);
PAINT GREEN (-1750 -250);
FORCEPROP 0 LASTPIN (-1500 -175) $PN A
J 0
(-1490 -165);
DISPLAY 0.808511 (-1490 -165);
FORCEPROP 0 LASTPIN (-1800 -175) $PN C
J 2
(-1810 -165);
DISPLAY 0.808511 (-1810 -165);
FORCEPROP 1 LAST PATH I9
J 2
(-1775 -95);
DISPLAY 0.723404 (-1775 -95);
PAINT GREEN (-1775 -95);
DISPLAY INVISIBLE (-1775 -95);
FORCEPROP 2 LAST CDS_LIB pure_quanta
J 0
(-1650 -175);
DISPLAY INVISIBLE (-1650 -175);
FORCEPROP 1 LAST NEEDS_NO_SIZE TRUE
J 2
(-1628 -153);
DISPLAY 0.468085 (-1628 -153);
PAINT GREEN (-1628 -153);
DISPLAY INVISIBLE (-1628 -153);
FORCEPROP 0 LAST $SEC 1
J 0
(-1750 -200);
DISPLAY INVISIBLE (-1750 -200);
FORCEPROP 0 LAST CDS_SEC 1
J 0
(-1750 -200);
DISPLAY INVISIBLE (-1750 -200);
FORCEADD QUANTA_TITLE_BLOCK_C..1
(5125 -1325);
FORCEPROP 0 LAST CDS_CON_LAST_MODIFIED Fri Aug 25 14:04:27 2023
J 0
(3240 -1310);
DISPLAY INVISIBLE (3240 -1310);
FORCEPROP 1 LAST CUSTOM_TXT_CDS <CON_LAST_MODIFIED>
J 0
(3240 -1310);
DISPLAY 0.978723 (3240 -1310);
FORCEPROP 2 LAST CUSTOM_TXT_CDS <XR_PAGE_TITLE>
J 0
(-2765 3925);
DISPLAY 0.638298 (-2765 3925);
PAINT PINK (-2765 3925);
DISPLAY INVISIBLE (-2765 3925);
FORCEPROP 1 LAST CUSTOM_TXT_CDS <NAME_2>
J 0
(1950 -1275);
FORCEPROP 1 LAST CUSTOM_TXT_CDS <NAME_1>
J 0
(1950 -1150);
FORCEPROP 1 LAST CUSTOM_TXT_CDS <Q_NUMBER>
J 0
(3722 -1222);
DISPLAY 1.212766 (3722 -1222);
FORCEPROP 1 LAST CUSTOM_TXT_CDS <Q_PROJ>
J 0
(2743 -1223);
DISPLAY 1.212766 (2743 -1223);
FORCEPROP 1 LAST CUSTOM_TXT_CDS <Q_REV>
J 0
(4941 -1222);
DISPLAY 1.212766 (4941 -1222);
FORCEPROP 1 LAST CUSTOM_TXT_CDS <CON_PAGE_NUM> OF <CON_TOTAL_PAGES>
J 0
(4679 -1307);
DISPLAY 0.978723 (4679 -1307);
FORCEPROP 1 LAST Q_TITLE POWER GOOD LED'S 5/5
J 0
(-4241 -1299);
DISPLAY 2.446809 (-4241 -1299);
PAINT GREEN (-4241 -1299);
FORCEPROP 1 LAST Q_DEPT 
J 1
(1362 -1276);
DISPLAY 1.957447 (1362 -1276);
PAINT GREEN (1362 -1276);
FORCEPROP 2 LAST CDS_XR_PAGE_TITLE CR-256 : @S9S_MB_2U_LIB.S9S_MB_2U(SCH_1):PAGE256
J 0
(-2765 3925);
DISPLAY 0.638298 (-2765 3925);
PAINT PINK (-2765 3925);
DISPLAY INVISIBLE (-2765 3925);
FORCEPROP 2 LAST CDS_LIB pure_quanta
J 0
(5125 -1325);
DISPLAY INVISIBLE (5125 -1325);
FORCEPROP 1 LAST CDS_LMAN_SYM_OUTLINE -9475,6775,100,-125
J 0
(5125 -1325);
DISPLAY 0.468085 (5125 -1325);
PAINT GREEN (5125 -1325);
DISPLAY INVISIBLE (5125 -1325);
FORCEPROP 2 LAST PAGE_BORDER TRUE
J 0
(-2765 3925);
DISPLAY 0.638298 (-2765 3925);
PAINT PINK (-2765 3925);
DISPLAY INVISIBLE (-2765 3925);
FORCEPROP 1 LAST COMMENT_BODY TRUE
J 0
(5137 -1338);
DISPLAY 0.978723 (5137 -1338);
PAINT GREEN (5137 -1338);
DISPLAY INVISIBLE (5137 -1338);
WIRE 16 -1 (175 4450)(175 4550);
WIRE 16 -1 (175 4450)(-300 4450);
WIRE 16 -1 (275 -175)(275 -50);
WIRE 16 -1 (275 -175)(-250 -175);
WIRE 16 -1 (150 1175)(150 1300);
WIRE 16 -1 (150 1175)(-400 1175);
WIRE 16 -1 (175 2850)(175 2975);
WIRE 16 -1 (175 2850)(-375 2850);
WIRE 16 -1 (4675 1250)(4675 1375);
WIRE 16 -1 (4675 1250)(4125 1250);
WIRE 16 -1 (4800 -100)(4800 25);
WIRE 16 -1 (4800 -100)(4275 -100);
WIRE 16 -1 (4675 4425)(4675 4550);
WIRE 16 -1 (4675 4425)(4100 4425);
WIRE 16 -1 (4750 3000)(4750 3125);
WIRE 16 -1 (4750 3000)(4200 3000);
WIRE 16 -1 (1675 2450)(1675 2525);
WIRE 16 -1 (1675 3850)(1675 3950);
WIRE 16 -1 (1700 675)(1700 775);
WIRE 16 -1 (1900 -750)(1900 -575);
WIRE 16 -1 (-2625 -825)(-2625 -650);
WIRE 16 -1 (-2825 600)(-2825 700);
WIRE 16 -1 (-2800 3875)(-2800 3975);
WIRE 16 -1 (-2800 2275)(-2800 2375);
WIRE 74 -1 (2850 450)(700 450);
WIRE 74 -1 (2850 250)(2850 450);
WIRE 74 -1 (700 450)(700 250);
WIRE 74 -1 (700 250)(2850 250);
WIRE 16 -1 (-1500 -175)(-450 -175);
FORCEPROP 2 LAST SIG_NAME LED_RST_PLD_CPU0_DRAM_GH_N
J 0
(-1335 -165);
DISPLAY 0.723404 (-1335 -165);
WIRE 74 -1 (-1675 375)(-3825 375);
WIRE 74 -1 (-1675 175)(-1675 375);
WIRE 74 -1 (-3825 375)(-3825 175);
WIRE 74 -1 (-3825 175)(-1675 175);
WIRE 16 -1 (-3075 850)(-3925 850);
FORCEPROP 2 LAST SIG_NAME RST_PLD_CPU0_DRAM_EF_N
J 0
(-3910 860);
DISPLAY 0.723404 (-3910 860);
WIRE 16 -1 (-3775 -500)(-2875 -500);
FORCEPROP 2 LAST SIG_NAME RST_PLD_CPU0_DRAM_GH_N
J 0
(-3710 -490);
DISPLAY 0.723404 (-3710 -490);
WIRE 16 -1 (-2825 1175)(-1950 1175);
WIRE 16 -1 (-2825 1100)(-2825 1175);
FORCEPROP 2 LAST SIG_NAME LED_RST_PLD_CPU0_DRAM_EF_N_D
J 0
(-2960 1175);
DISPLAY 0.723404 (-2960 1175);
WIRE 74 -1 (2775 1775)(625 1775);
WIRE 74 -1 (2775 1575)(2775 1775);
WIRE 74 -1 (625 1775)(625 1575);
WIRE 74 -1 (625 1575)(2775 1575);
WIRE 16 -1 (1425 4100)(575 4100);
FORCEPROP 2 LAST SIG_NAME RST_PLD_CPU1_DRAM_AB_N
J 0
(565 4110);
DISPLAY 0.723404 (565 4110);
WIRE 16 -1 (1675 4350)(1675 4425);
FORCEPROP 2 LAST SIG_NAME LED_RST_PLD_CPU1_DRAM_AB_N_D
J 0
(1540 4425);
DISPLAY 0.723404 (1540 4425);
WIRE 16 -1 (1675 4425)(2550 4425);
WIRE 74 -1 (2750 3525)(600 3525);
WIRE 74 -1 (2750 3325)(2750 3525);
WIRE 74 -1 (600 3525)(600 3325);
WIRE 74 -1 (600 3325)(2750 3325);
WIRE 16 -1 (1675 3000)(2550 3000);
WIRE 16 -1 (1675 2925)(1675 3000);
FORCEPROP 2 LAST SIG_NAME LED_RST_PLD_CPU1_DRAM_CD_N_D
J 0
(1515 3000);
DISPLAY 0.723404 (1515 3000);
WIRE 16 -1 (1425 2675)(675 2675);
FORCEPROP 2 LAST SIG_NAME RST_PLD_CPU1_DRAM_CD_N
J 0
(740 2685);
DISPLAY 0.723404 (740 2685);
WIRE 16 -1 (-1625 2850)(-575 2850);
FORCEPROP 2 LAST SIG_NAME LED_RST_PLD_CPU0_DRAM_CD_N
J 0
(-1460 2860);
DISPLAY 0.723404 (-1460 2860);
WIRE 74 -1 (-1725 3375)(-3875 3375);
WIRE 74 -1 (-1725 3175)(-1725 3375);
WIRE 74 -1 (-3875 3375)(-3875 3175);
WIRE 74 -1 (-3875 3175)(-1725 3175);
WIRE 16 -1 (-2800 2850)(-1925 2850);
WIRE 16 -1 (-2800 2775)(-2800 2850);
FORCEPROP 2 LAST SIG_NAME LED_RST_PLD_CPU0_DRAM_CD_N_D
J 0
(-2960 2850);
DISPLAY 0.723404 (-2960 2850);
WIRE 16 -1 (-3050 2525)(-3900 2525);
FORCEPROP 2 LAST SIG_NAME RST_PLD_CPU0_DRAM_CD_N
J 0
(-3935 2535);
DISPLAY 0.723404 (-3935 2535);
WIRE 16 -1 (1700 1250)(2575 1250);
WIRE 16 -1 (1700 1175)(1700 1250);
FORCEPROP 2 LAST SIG_NAME LED_RST_PLD_CPU1_DRAM_EF_N_D
J 0
(1565 1250);
DISPLAY 0.723404 (1565 1250);
WIRE 16 -1 (2875 1250)(3925 1250);
FORCEPROP 2 LAST SIG_NAME LED_RST_PLD_CPU1_DRAM_EF_N
J 0
(3040 1260);
DISPLAY 0.723404 (3040 1260);
WIRE 16 -1 (1450 925)(600 925);
FORCEPROP 2 LAST SIG_NAME RST_PLD_CPU1_DRAM_EF_N
J 0
(665 935);
DISPLAY 0.723404 (665 935);
WIRE 16 -1 (1900 -175)(1900 -100);
FORCEPROP 2 LAST SIG_NAME LED_RST_PLD_CPU1_DRAM_GH_N_D
J 0
(1665 -100);
DISPLAY 0.723404 (1665 -100);
WIRE 16 -1 (1900 -100)(2725 -100);
WIRE 16 -1 (750 -425)(1650 -425);
FORCEPROP 2 LAST SIG_NAME RST_PLD_CPU1_DRAM_GH_N
J 0
(815 -415);
DISPLAY 0.723404 (815 -415);
WIRE 16 -1 (3025 -100)(4075 -100);
FORCEPROP 2 LAST SIG_NAME LED_RST_PLD_CPU1_DRAM_GH_N
J 0
(3190 -90);
DISPLAY 0.723404 (3190 -90);
WIRE 16 -1 (-2625 -250)(-2625 -175);
FORCEPROP 2 LAST SIG_NAME LED_RST_PLD_CPU0_DRAM_GH_N_D
J 0
(-2810 -175);
DISPLAY 0.723404 (-2810 -175);
WIRE 16 -1 (-2625 -175)(-1800 -175);
WIRE 74 -1 (-1750 1700)(-3900 1700);
WIRE 74 -1 (-1750 1500)(-1750 1700);
WIRE 74 -1 (-3900 1700)(-3900 1500);
WIRE 74 -1 (-3900 1500)(-1750 1500);
WIRE 16 -1 (-3050 4125)(-3900 4125);
FORCEPROP 2 LAST SIG_NAME RST_PLD_CPU0_DRAM_AB_N
J 0
(-3885 4135);
DISPLAY 0.723404 (-3885 4135);
WIRE 16 -1 (-2800 4375)(-2800 4450);
FORCEPROP 2 LAST SIG_NAME LED_RST_PLD_CPU0_DRAM_AB_N_D
J 0
(-2935 4450);
DISPLAY 0.723404 (-2935 4450);
WIRE 16 -1 (-2800 4450)(-1925 4450);
WIRE 74 -1 (-1725 4975)(-3875 4975);
WIRE 74 -1 (-1725 4775)(-1725 4975);
WIRE 74 -1 (-3875 4975)(-3875 4775);
WIRE 74 -1 (-3875 4775)(-1725 4775);
WIRE 74 -1 (2750 4950)(600 4950);
WIRE 74 -1 (2750 4750)(2750 4950);
WIRE 74 -1 (600 4950)(600 4750);
WIRE 74 -1 (600 4750)(2750 4750);
WIRE 16 -1 (-1650 1175)(-600 1175);
FORCEPROP 2 LAST SIG_NAME LED_RST_PLD_CPU0_DRAM_EF_N
J 0
(-1485 1185);
DISPLAY 0.723404 (-1485 1185);
WIRE 16 -1 (-1625 4450)(-500 4450);
FORCEPROP 2 LAST SIG_NAME LED_RST_PLD_CPU0_DRAM_AB_N
J 0
(-1560 4460);
DISPLAY 0.723404 (-1560 4460);
WIRE 16 -1 (2850 3000)(4000 3000);
FORCEPROP 2 LAST SIG_NAME LED_RST_PLD_CPU1_DRAM_CD_N
J 0
(3015 3010);
DISPLAY 0.723404 (3015 3010);
WIRE 16 -1 (2850 4425)(3900 4425);
FORCEPROP 2 LAST SIG_NAME LED_RST_PLD_CPU1_DRAM_AB_N
J 0
(3015 4435);
DISPLAY 0.723404 (3015 4435);
FORCENOTE
20210705 MODIFY FOR GT
(-1750 5125) 0;
DISPLAY LEFT (-1750 5125);
DISPLAY 2.510638 (-1750 5125);
PAINT PINK (-1750 5125);
FORCENOTE
RST_CPU1_DRAM_AB          1 = ON
(725 4825) 0;
DISPLAY LEFT (725 4825);
DISPLAY 1.276596 (725 4825);
PAINT WHITE (725 4825);
FORCENOTE
RST_CPU0_DRAM_AB          1 = ON
(-3750 4850) 0;
DISPLAY LEFT (-3750 4850);
DISPLAY 1.276596 (-3750 4850);
PAINT WHITE (-3750 4850);
FORCENOTE
RST_CPU0_DRAM_CD          1 = ON
(-3750 3250) 0;
DISPLAY LEFT (-3750 3250);
DISPLAY 1.276596 (-3750 3250);
PAINT WHITE (-3750 3250);
FORCENOTE
RST_CPU1_DRAM_CD          1 = ON
(725 3400) 0;
DISPLAY LEFT (725 3400);
DISPLAY 1.276596 (725 3400);
PAINT WHITE (725 3400);
FORCENOTE
RST_CPU1_DRAM_EF          1 = ON
(750 1650) 0;
DISPLAY LEFT (750 1650);
DISPLAY 1.276596 (750 1650);
PAINT WHITE (750 1650);
FORCENOTE
RST_CPU1_DRAM_GH          1 = ON
(825 325) 0;
DISPLAY LEFT (825 325);
DISPLAY 1.276596 (825 325);
PAINT WHITE (825 325);
FORCENOTE
RST_CPU0_DRAM_GH          1 = ON
(-3700 250) 0;
DISPLAY LEFT (-3700 250);
DISPLAY 1.276596 (-3700 250);
PAINT WHITE (-3700 250);
FORCENOTE
RST_CPU0_DRAM_EF          1 = ON
(-3775 1575) 0;
DISPLAY LEFT (-3775 1575);
DISPLAY 1.276596 (-3775 1575);
PAINT WHITE (-3775 1575);
QUIT
